# T6G (Grand Teton) — schematic netlist excerpt (pin names and nets, part order shuffled) for the footprints in the layout excerpt that follows; sources: Cadence DE-HDL packaged netlist, KiCad conversion of 04192023_DAF0TMB3IC0_F0TG_MB_C_brd_V02_OCP.brd

PR435  Q_RES  0 5% CHIP  pkg 0402LF  page 209 : A = PVDD18_S5_P0_RGND ; B = VSENSE_PVDD18_S5_P0_DN
PR392  Q_RES  0 5% EMPTY  pkg 0402LF  page 224 : A = PVDD11_S3_P1_RESET_N_R ; B = PVDD11_S3_P1_RESET_N

(kicad_pcb
	(version 20260206)
	(generator "pcbnew")
	(generator_version "10.0")
	(general
		(thickness 1.6)
		(legacy_teardrops no)
	)
	(paper "A4")
	(title_block
		(title "04192023_DAF0TMB3IC0_F0TG_MB_C_brd_V02_OCP.brd")
		(comment 1 "Grand Teton / footprints 3096-3097 of 8354")
	)
	(layers
		(0 "F.Cu" signal "TOP")
		(4 "In1.Cu" signal "GND")
		(6 "In2.Cu" signal "IN1")
		(8 "In3.Cu" signal "GND1")
		(10 "In4.Cu" signal "IN2")
		(12 "In5.Cu" signal "GND2")
		(14 "In6.Cu" signal "IN3")
		(16 "In7.Cu" signal "GND3")
		(18 "In8.Cu" signal "VCC")
		(20 "In9.Cu" signal "VCC1")
		(22 "In10.Cu" signal "GND4")
		(24 "In11.Cu" signal "IN4")
		(26 "In12.Cu" signal "GND5")
		(28 "In13.Cu" signal "IN5")
		(30 "In14.Cu" signal "GND6")
		(32 "In15.Cu" signal "IN6")
		(34 "In16.Cu" signal "GND7")
		(2 "B.Cu" signal "BOTTOM")
		(9 "F.Adhes" user "F.Adhesive")
		(11 "B.Adhes" user "B.Adhesive")
		(13 "F.Paste" user "Package Geometry/Pastemask Top")
		(15 "B.Paste" user "Package Geometry/Pastemask Bottom")
		(5 "F.SilkS" user "Ref Des/Silkscreen Top")
		(7 "B.SilkS" user "Ref Des/Silkscreen Bottom")
		(1 "F.Mask" user "Board Geometry/Soldermask Top")
		(3 "B.Mask" user "Board Geometry/Soldermask Bottom")
		(17 "Dwgs.User" user "User.Drawings")
		(19 "Cmts.User" user "User.Comments")
		(21 "Eco1.User" user "User.Eco1")
		(23 "Eco2.User" user "User.Eco2")
		(25 "Edge.Cuts" user "Board Geometry/Outline")
		(27 "Margin" user)
		(31 "F.CrtYd" user "Package Geometry/Place Bound Top")
		(29 "B.CrtYd" user "Package Geometry/Place Bound Bottom")
		(35 "F.Fab" user "Ref Des/Assembly Top")
		(33 "B.Fab" user "Ref Des/Assembly Bottom")
	)
	(footprint ""
		(layer "F.Cu")
		(at 157.686502 -348.280228 180)
		(property "Reference" "PR392"
			(at 0 0 180)
			(layer "F.SilkS")
			(hide yes)
			(effects
				(font
					(size 1.27 1.27)
				)
			)
		)
		(property "Value" ""
			(at 0 0 180)
			(layer "F.Fab")
			(effects
				(font
					(size 1.27 1.27)
				)
			)
		)
		(duplicate_pad_numbers_are_jumpers no)
		(fp_line
			(start 0.7874 0.4064)
			(end -0.7874 0.4064)
			(stroke
				(width 0.1524)
				(type default)
			)
			(layer "F.SilkS")
		)
		(fp_line
			(start 0.7874 -0.4064)
			(end 0.7874 0.4064)
			(stroke
				(width 0.1524)
				(type default)
			)
			(layer "F.SilkS")
		)
		(fp_line
			(start -0.7874 0.4064)
			(end -0.7874 -0.4064)
			(stroke
				(width 0.1524)
				(type default)
			)
			(layer "F.SilkS")
		)
		(fp_line
			(start -0.7874 -0.4064)
			(end 0.7874 -0.4064)
			(stroke
				(width 0.1524)
				(type default)
			)
			(layer "F.SilkS")
		)
		(fp_line
			(start 0.67945 0.3048)
			(end 0.120396 0.3048)
			(stroke
				(width 0.1)
				(type default)
			)
			(layer "F.Fab")
		)
		(fp_line
			(start 0.67945 -0.3048)
			(end 0.67945 0.3048)
			(stroke
				(width 0.1)
				(type default)
			)
			(layer "F.Fab")
		)
		(fp_line
			(start 0.12065 -0.2794)
			(end 0.12065 -0.3048)
			(stroke
				(width 0.1)
				(type default)
			)
			(layer "F.Fab")
		)
		(fp_line
			(start 0.12065 -0.3048)
			(end 0.67945 -0.3048)
			(stroke
				(width 0.1)
				(type default)
			)
			(layer "F.Fab")
		)
		(fp_line
			(start 0.120396 0.3048)
			(end 0.120396 0.2794)
			(stroke
				(width 0.1)
				(type default)
			)
			(layer "F.Fab")
		)
		(fp_line
			(start 0.120396 0.2794)
			(end -0.12065 0.2794)
			(stroke
				(width 0.1)
				(type default)
			)
			(layer "F.Fab")
		)
		(fp_line
			(start -0.12065 0.3048)
			(end -0.67945 0.3048)
			(stroke
				(width 0.1)
				(type default)
			)
			(layer "F.Fab")
		)
		(fp_line
			(start -0.12065 0.2794)
			(end -0.12065 0.3048)
			(stroke
				(width 0.1)
				(type default)
			)
			(layer "F.Fab")
		)
		(fp_line
			(start -0.12065 -0.2794)
			(end 0.12065 -0.2794)
			(stroke
				(width 0.1)
				(type default)
			)
			(layer "F.Fab")
		)
		(fp_line
			(start -0.12065 -0.305054)
			(end -0.12065 -0.2794)
			(stroke
				(width 0.1)
				(type default)
			)
			(layer "F.Fab")
		)
		(fp_line
			(start -0.67945 0.3048)
			(end -0.67945 -0.305054)
			(stroke
				(width 0.1)
				(type default)
			)
			(layer "F.Fab")
		)
		(fp_line
			(start -0.67945 -0.305054)
			(end -0.12065 -0.305054)
			(stroke
				(width 0.1)
				(type default)
			)
			(layer "F.Fab")
		)
		(pad "1" smd circle
			(at -0.40005 0 180)
			(size 0 0)
			(layers "F.Cu" "F.Mask" "F.Paste")
			(net "PVDD11_S3_P1_RESET_N_R")
		)
		(pad "2" smd circle
			(at 0.40005 0 180)
			(size 0 0)
			(layers "F.Cu" "F.Mask" "F.Paste")
			(net "PVDD11_S3_P1_RESET_N")
		)
	)
	(footprint ""
		(layer "F.Cu")
		(at 329.223624 -141.591792 90)
		(property "Reference" "PR435"
			(at 0 0 90)
			(layer "F.SilkS")
			(hide yes)
			(effects
				(font
					(size 1.27 1.27)
				)
			)
		)
		(property "Value" ""
			(at 0 0 90)
			(layer "F.Fab")
			(effects
				(font
					(size 1.27 1.27)
				)
			)
		)
		(duplicate_pad_numbers_are_jumpers no)
		(fp_line
			(start 0.7874 -0.4064)
			(end 0.7874 0.4064)
			(stroke
				(width 0.1524)
				(type default)
			)
			(layer "F.SilkS")
		)
		(fp_line
			(start -0.7874 -0.4064)
			(end 0.7874 -0.4064)
			(stroke
				(width 0.1524)
				(type default)
			)
			(layer "F.SilkS")
		)
		(fp_line
			(start 0.7874 0.4064)
			(end -0.7874 0.4064)
			(stroke
				(width 0.1524)
				(type default)
			)
			(layer "F.SilkS")
		)
		(fp_line
			(start -0.7874 0.4064)
			(end -0.7874 -0.4064)
			(stroke
				(width 0.1524)
				(type default)
			)
			(layer "F.SilkS")
		)
		(fp_line
			(start -0.12065 -0.305054)
			(end -0.12065 -0.2794)
			(stroke
				(width 0.1)
				(type default)
			)
			(layer "F.Fab")
		)
		(fp_line
			(start -0.67945 -0.305054)
			(end -0.12065 -0.305054)
			(stroke
				(width 0.1)
				(type default)
			)
			(layer "F.Fab")
		)
		(fp_line
			(start 0.67945 -0.3048)
			(end 0.67945 0.3048)
			(stroke
				(width 0.1)
				(type default)
			)
			(layer "F.Fab")
		)
		(fp_line
			(start 0.12065 -0.3048)
			(end 0.67945 -0.3048)
			(stroke
				(width 0.1)
				(type default)
			)
			(layer "F.Fab")
		)
		(fp_line
			(start 0.12065 -0.2794)
			(end 0.12065 -0.3048)
			(stroke
				(width 0.1)
				(type default)
			)
			(layer "F.Fab")
		)
		(fp_line
			(start -0.12065 -0.2794)
			(end 0.12065 -0.2794)
			(stroke
				(width 0.1)
				(type default)
			)
			(layer "F.Fab")
		)
		(fp_line
			(start 0.120396 0.2794)
			(end -0.12065 0.2794)
			(stroke
				(width 0.1)
				(type default)
			)
			(layer "F.Fab")
		)
		(fp_line
			(start -0.12065 0.2794)
			(end -0.12065 0.3048)
			(stroke
				(width 0.1)
				(type default)
			)
			(layer "F.Fab")
		)
		(fp_line
			(start 0.67945 0.3048)
			(end 0.120396 0.3048)
			(stroke
				(width 0.1)
				(type default)
			)
			(layer "F.Fab")
		)
		(fp_line
			(start 0.120396 0.3048)
			(end 0.120396 0.2794)
			(stroke
				(width 0.1)
				(type default)
			)
			(layer "F.Fab")
		)
		(fp_line
			(start -0.12065 0.3048)
			(end -0.67945 0.3048)
			(stroke
				(width 0.1)
				(type default)
			)
			(layer "F.Fab")
		)
		(fp_line
			(start -0.67945 0.3048)
			(end -0.67945 -0.305054)
			(stroke
				(width 0.1)
				(type default)
			)
			(layer "F.Fab")
		)
		(pad "1" smd circle
			(at -0.40005 0 90)
			(size 0 0)
			(layers "F.Cu" "F.Mask" "F.Paste")
			(net "PVDD18_S5_P0_RGND")
		)
		(pad "2" smd circle
			(at 0.40005 0 90)
			(size 0 0)
			(layers "F.Cu" "F.Mask" "F.Paste")
			(net "VSENSE_PVDD18_S5_P0_DN")
		)
	)
)
